# T6G (Grand Teton) — schematic netlist excerpt (pin names and nets, part order shuffled) for the footprints in the layout excerpt that follows; sources: Cadence DE-HDL packaged netlist, KiCad conversion of 04192023_DAF0TMB3IC0_F0TG_MB_C_brd_V02_OCP.brd

R3707  Q_RES  1K 1% CHIP  pkg 0402LF  page 252 : A = PCA9548_PCIE0_ADDR1 ; B = GND
C7037  Q_CAPP  470UF 2.5V 20% SPCAP  pkg SMLF  page 345 : A = P0V9_CPU1_RT_2D ; B = GND

(kicad_pcb
	(version 20260206)
	(generator "pcbnew")
	(generator_version "10.0")
	(general
		(thickness 1.6)
		(legacy_teardrops no)
	)
	(paper "A4")
	(title_block
		(title "04192023_DAF0TMB3IC0_F0TG_MB_C_brd_V02_OCP.brd")
		(comment 1 "Grand Teton / footprints 4762-4763 of 8354")
	)
	(layers
		(0 "F.Cu" signal "TOP")
		(4 "In1.Cu" signal "GND")
		(6 "In2.Cu" signal "IN1")
		(8 "In3.Cu" signal "GND1")
		(10 "In4.Cu" signal "IN2")
		(12 "In5.Cu" signal "GND2")
		(14 "In6.Cu" signal "IN3")
		(16 "In7.Cu" signal "GND3")
		(18 "In8.Cu" signal "VCC")
		(20 "In9.Cu" signal "VCC1")
		(22 "In10.Cu" signal "GND4")
		(24 "In11.Cu" signal "IN4")
		(26 "In12.Cu" signal "GND5")
		(28 "In13.Cu" signal "IN5")
		(30 "In14.Cu" signal "GND6")
		(32 "In15.Cu" signal "IN6")
		(34 "In16.Cu" signal "GND7")
		(2 "B.Cu" signal "BOTTOM")
		(9 "F.Adhes" user "F.Adhesive")
		(11 "B.Adhes" user "B.Adhesive")
		(13 "F.Paste" user "Package Geometry/Pastemask Top")
		(15 "B.Paste" user "Package Geometry/Pastemask Bottom")
		(5 "F.SilkS" user "Ref Des/Silkscreen Top")
		(7 "B.SilkS" user "Ref Des/Silkscreen Bottom")
		(1 "F.Mask" user "Board Geometry/Soldermask Top")
		(3 "B.Mask" user "Board Geometry/Soldermask Bottom")
		(17 "Dwgs.User" user "User.Drawings")
		(19 "Cmts.User" user "User.Comments")
		(21 "Eco1.User" user "User.Eco1")
		(23 "Eco2.User" user "User.Eco2")
		(25 "Edge.Cuts" user "Board Geometry/Outline")
		(27 "Margin" user)
		(31 "F.CrtYd" user "Package Geometry/Place Bound Top")
		(29 "B.CrtYd" user "Package Geometry/Place Bound Bottom")
		(35 "F.Fab" user "Ref Des/Assembly Top")
		(33 "B.Fab" user "Ref Des/Assembly Bottom")
	)
	(footprint ""
		(layer "F.Cu")
		(at 57.88914 -400.755612)
		(property "Reference" "C7037"
			(at -5.0038 4.043172 0)
			(unlocked yes)
			(layer "F.SilkS")
			(effects
				(font
					(size 0.7874 0.5842)
					(thickness 0.1524)
				)
				(justify left)
			)
		)
		(property "Value" ""
			(at 0 0 0)
			(layer "F.Fab")
			(effects
				(font
					(size 1.27 1.27)
				)
			)
		)
		(duplicate_pad_numbers_are_jumpers no)
		(fp_line
			(start -4.84378 -2.150618)
			(end -4.842256 2.163064)
			(stroke
				(width 0.1524)
				(type default)
			)
			(layer "F.SilkS")
		)
		(fp_line
			(start -4.84378 -2.150618)
			(end -4.53898 -2.150618)
			(stroke
				(width 0.1524)
				(type default)
			)
			(layer "F.SilkS")
		)
		(fp_line
			(start -4.83108 2.150364)
			(end -4.447794 2.149348)
			(stroke
				(width 0.1524)
				(type default)
			)
			(layer "F.SilkS")
		)
		(fp_line
			(start -4.69138 -2.150618)
			(end -4.692396 2.161032)
			(stroke
				(width 0.1524)
				(type default)
			)
			(layer "F.SilkS")
		)
		(fp_line
			(start -4.53898 -2.150618)
			(end -4.539742 2.152142)
			(stroke
				(width 0.1524)
				(type default)
			)
			(layer "F.SilkS")
		)
		(fp_line
			(start -4.53898 -2.15011)
			(end 4.53898 -2.15011)
			(stroke
				(width 0.1524)
				(type default)
			)
			(layer "F.SilkS")
		)
		(fp_line
			(start -4.53898 2.15011)
			(end -4.53898 -2.15011)
			(stroke
				(width 0.1524)
				(type default)
			)
			(layer "F.SilkS")
		)
		(fp_line
			(start 4.53898 -2.15011)
			(end 4.53898 2.15011)
			(stroke
				(width 0.1524)
				(type default)
			)
			(layer "F.SilkS")
		)
		(fp_line
			(start 4.53898 2.15011)
			(end -4.53898 2.15011)
			(stroke
				(width 0.1524)
				(type default)
			)
			(layer "F.SilkS")
		)
		(fp_line
			(start -3.64998 -2.15011)
			(end 3.64998 -2.15011)
			(stroke
				(width 0.1)
				(type default)
			)
			(layer "F.Fab")
		)
		(fp_line
			(start -3.64998 2.15011)
			(end -3.64998 -2.15011)
			(stroke
				(width 0.1)
				(type default)
			)
			(layer "F.Fab")
		)
		(fp_line
			(start 3.64998 -2.15011)
			(end 3.64998 2.15011)
			(stroke
				(width 0.1)
				(type default)
			)
			(layer "F.Fab")
		)
		(fp_line
			(start 3.64998 2.15011)
			(end -3.64998 2.15011)
			(stroke
				(width 0.1)
				(type default)
			)
			(layer "F.Fab")
		)
		(fp_text user "+"
			(at -4.754372 2.619502 0)
			(unlocked yes)
			(layer "F.SilkS")
			(effects
				(font
					(size 1.905 1.4224)
					(thickness 0.1524)
				)
				(justify left)
			)
		)
		(fp_text user "-"
			(at 3.096514 -2.753868 0)
			(unlocked yes)
			(layer "F.SilkS")
			(effects
				(font
					(size 1.905 1.4224)
					(thickness 0.1524)
				)
				(justify left)
			)
		)
		(fp_text user "+"
			(at -6.214872 -0.337058 0)
			(unlocked yes)
			(layer "F.Fab")
			(effects
				(font
					(size 1.905 1.4224)
					(thickness 0.1524)
				)
				(justify left)
			)
		)
		(fp_text user "-"
			(at 4.313174 -0.094488 0)
			(unlocked yes)
			(layer "F.Fab")
			(effects
				(font
					(size 1.905 1.4224)
					(thickness 0.1524)
				)
				(justify left)
			)
		)
		(pad "1" smd rect
			(at -3.199892 0)
			(size 2.413 2.8194)
			(layers "F.Cu" "F.Mask" "F.Paste")
			(net "P0V9_CPU1_RT_2D")
		)
		(pad "2" smd rect
			(at 3.199892 0)
			(size 2.413 2.8194)
			(layers "F.Cu" "F.Mask" "F.Paste")
			(net "GND")
		)
	)
	(footprint ""
		(layer "F.Cu")
		(at 257.242056 -124.115068 180)
		(property "Reference" "R3707"
			(at 0 0 180)
			(layer "F.SilkS")
			(hide yes)
			(effects
				(font
					(size 1.27 1.27)
				)
			)
		)
		(property "Value" ""
			(at 0 0 180)
			(layer "F.Fab")
			(effects
				(font
					(size 1.27 1.27)
				)
			)
		)
		(duplicate_pad_numbers_are_jumpers no)
		(fp_line
			(start 0.7874 0.4064)
			(end -0.7874 0.4064)
			(stroke
				(width 0.1524)
				(type default)
			)
			(layer "F.SilkS")
		)
		(fp_line
			(start 0.7874 -0.4064)
			(end 0.7874 0.4064)
			(stroke
				(width 0.1524)
				(type default)
			)
			(layer "F.SilkS")
		)
		(fp_line
			(start -0.7874 0.4064)
			(end -0.7874 -0.4064)
			(stroke
				(width 0.1524)
				(type default)
			)
			(layer "F.SilkS")
		)
		(fp_line
			(start -0.7874 -0.4064)
			(end 0.7874 -0.4064)
			(stroke
				(width 0.1524)
				(type default)
			)
			(layer "F.SilkS")
		)
		(fp_line
			(start 0.67945 0.3048)
			(end 0.120396 0.3048)
			(stroke
				(width 0.1)
				(type default)
			)
			(layer "F.Fab")
		)
		(fp_line
			(start 0.67945 -0.3048)
			(end 0.67945 0.3048)
			(stroke
				(width 0.1)
				(type default)
			)
			(layer "F.Fab")
		)
		(fp_line
			(start 0.12065 -0.2794)
			(end 0.12065 -0.3048)
			(stroke
				(width 0.1)
				(type default)
			)
			(layer "F.Fab")
		)
		(fp_line
			(start 0.12065 -0.3048)
			(end 0.67945 -0.3048)
			(stroke
				(width 0.1)
				(type default)
			)
			(layer "F.Fab")
		)
		(fp_line
			(start 0.120396 0.3048)
			(end 0.120396 0.2794)
			(stroke
				(width 0.1)
				(type default)
			)
			(layer "F.Fab")
		)
		(fp_line
			(start 0.120396 0.2794)
			(end -0.12065 0.2794)
			(stroke
				(width 0.1)
				(type default)
			)
			(layer "F.Fab")
		)
		(fp_line
			(start -0.12065 0.3048)
			(end -0.67945 0.3048)
			(stroke
				(width 0.1)
				(type default)
			)
			(layer "F.Fab")
		)
		(fp_line
			(start -0.12065 0.2794)
			(end -0.12065 0.3048)
			(stroke
				(width 0.1)
				(type default)
			)
			(layer "F.Fab")
		)
		(fp_line
			(start -0.12065 -0.2794)
			(end 0.12065 -0.2794)
			(stroke
				(width 0.1)
				(type default)
			)
			(layer "F.Fab")
		)
		(fp_line
			(start -0.12065 -0.305054)
			(end -0.12065 -0.2794)
			(stroke
				(width 0.1)
				(type default)
			)
			(layer "F.Fab")
		)
		(fp_line
			(start -0.67945 0.3048)
			(end -0.67945 -0.305054)
			(stroke
				(width 0.1)
				(type default)
			)
			(layer "F.Fab")
		)
		(fp_line
			(start -0.67945 -0.305054)
			(end -0.12065 -0.305054)
			(stroke
				(width 0.1)
				(type default)
			)
			(layer "F.Fab")
		)
		(pad "1" smd circle
			(at -0.40005 0 180)
			(size 0 0)
			(layers "F.Cu" "F.Mask" "F.Paste")
			(net "PCA9548_PCIE0_ADDR1")
		)
		(pad "2" smd circle
			(at 0.40005 0 180)
			(size 0 0)
			(layers "F.Cu" "F.Mask" "F.Paste")
			(net "GND")
		)
	)
)
